(kicad_pcb
	(version 20260206)
	(generator "pcbnew")
	(generator_version "10.0")
	(general
		(thickness 1.6)
		(legacy_teardrops no)
	)
	(paper "A4")
	(title_block
		(title "04192023_DAF0TMB3IC0_F0TG_MB_C_brd_V02_OCP.brd")
		(comment 1 "Grand Teton / footprints 2529-2534 of 8354")
	)
	(layers
		(0 "F.Cu" signal "TOP")
		(4 "In1.Cu" signal "GND")
		(6 "In2.Cu" signal "IN1")
		(8 "In3.Cu" signal "GND1")
		(10 "In4.Cu" signal "IN2")
		(12 "In5.Cu" signal "GND2")
		(14 "In6.Cu" signal "IN3")
		(16 "In7.Cu" signal "GND3")
		(18 "In8.Cu" signal "VCC")
		(20 "In9.Cu" signal "VCC1")
		(22 "In10.Cu" signal "GND4")
		(24 "In11.Cu" signal "IN4")
		(26 "In12.Cu" signal "GND5")
		(28 "In13.Cu" signal "IN5")
		(30 "In14.Cu" signal "GND6")
		(32 "In15.Cu" signal "IN6")
		(34 "In16.Cu" signal "GND7")
		(2 "B.Cu" signal "BOTTOM")
		(9 "F.Adhes" user "F.Adhesive")
		(11 "B.Adhes" user "B.Adhesive")
		(13 "F.Paste" user "Package Geometry/Pastemask Top")
		(15 "B.Paste" user "Package Geometry/Pastemask Bottom")
		(5 "F.SilkS" user "Ref Des/Silkscreen Top")
		(7 "B.SilkS" user "Ref Des/Silkscreen Bottom")
		(1 "F.Mask" user "Board Geometry/Soldermask Top")
		(3 "B.Mask" user "Board Geometry/Soldermask Bottom")
		(17 "Dwgs.User" user "User.Drawings")
		(19 "Cmts.User" user "User.Comments")
		(21 "Eco1.User" user "User.Eco1")
		(23 "Eco2.User" user "User.Eco2")
		(25 "Edge.Cuts" user "Board Geometry/Outline")
		(27 "Margin" user)
		(31 "F.CrtYd" user "Package Geometry/Place Bound Top")
		(29 "B.CrtYd" user "Package Geometry/Place Bound Bottom")
		(35 "F.Fab" user "Ref Des/Assembly Top")
		(33 "B.Fab" user "Ref Des/Assembly Bottom")
	)
	(footprint ""
		(layer "F.Cu")
		(at 143.46174 -78.287626)
		(property "Reference" "PU6000"
			(at -5.757672 -4.30784 0)
			(unlocked yes)
			(layer "F.SilkS")
			(effects
				(font
					(size 0.7874 0.5842)
					(thickness 0.1524)
				)
				(justify left)
			)
		)
		(property "Value" ""
			(at 0 0 0)
			(layer "F.Fab")
			(effects
				(font
					(size 1.27 1.27)
				)
			)
		)
		(duplicate_pad_numbers_are_jumpers no)
		(fp_line
			(start -1.050036 -1.549908)
			(end -0.503936 -1.549908)
			(stroke
				(width 0.1524)
				(type default)
			)
			(layer "F.SilkS")
		)
		(fp_line
			(start -1.050036 -1.253998)
			(end -1.050036 -1.549908)
			(stroke
				(width 0.1524)
				(type default)
			)
			(layer "F.SilkS")
		)
		(fp_line
			(start -1.050036 1.549908)
			(end -1.050036 1.253998)
			(stroke
				(width 0.1524)
				(type default)
			)
			(layer "F.SilkS")
		)
		(fp_line
			(start -0.503936 1.549908)
			(end -1.050036 1.549908)
			(stroke
				(width 0.1524)
				(type default)
			)
			(layer "F.SilkS")
		)
		(fp_line
			(start 0.503936 -1.549908)
			(end 1.050036 -1.549908)
			(stroke
				(width 0.1524)
				(type default)
			)
			(layer "F.SilkS")
		)
		(fp_line
			(start 1.050036 -1.549908)
			(end 1.050036 -1.253998)
			(stroke
				(width 0.1524)
				(type default)
			)
			(layer "F.SilkS")
		)
		(fp_line
			(start 1.050036 1.253998)
			(end 1.050036 1.549908)
			(stroke
				(width 0.1524)
				(type default)
			)
			(layer "F.SilkS")
		)
		(fp_line
			(start 1.050036 1.549908)
			(end 0.503936 1.549908)
			(stroke
				(width 0.1524)
				(type default)
			)
			(layer "F.SilkS")
		)
		(fp_poly
			(pts
				(xy -1.499616 -1.491488) (xy -2.307844 -1.760982) (xy -1.76911 -2.299716)
			)
			(stroke
				(width 0)
				(type default)
			)
			(fill yes)
			(layer "F.SilkS")
		)
		(fp_line
			(start -1.050036 -1.549908)
			(end 1.050036 -1.549908)
			(stroke
				(width 0.1)
				(type default)
			)
			(layer "F.Fab")
		)
		(fp_line
			(start -1.050036 1.549908)
			(end -1.050036 -1.549908)
			(stroke
				(width 0.1)
				(type default)
			)
			(layer "F.Fab")
		)
		(fp_line
			(start 1.050036 -1.549908)
			(end 1.050036 1.549908)
			(stroke
				(width 0.1)
				(type default)
			)
			(layer "F.Fab")
		)
		(fp_line
			(start 1.050036 1.549908)
			(end -1.050036 1.549908)
			(stroke
				(width 0.1)
				(type default)
			)
			(layer "F.Fab")
		)
		(fp_poly
			(pts
				(xy -2.2352 -0.618998) (xy -2.2352 -1.380998) (xy -1.4732 -0.999998)
			)
			(stroke
				(width 0)
				(type default)
			)
			(fill yes)
			(layer "F.Fab")
		)
		(pad "1" smd circle
			(at -0.94996 -0.999998 270)
			(size 0 0)
			(layers "F.Cu" "F.Mask" "F.Paste")
			(net "GND")
		)
		(pad "2" smd rect
			(at -0.849884 -0.499872 90)
			(size 0.254 0.9144)
			(layers "F.Cu" "F.Mask" "F.Paste")
			(net "SW_P1V8_AUX_PH")
		)
		(pad "3" smd rect
			(at -0.649986 0 90)
			(size 0.254 1.3208)
			(layers "F.Cu" "F.Mask" "F.Paste")
			(net "SW_P12V_AUX_P1V8_AUX_FLT")
		)
		(pad "4" smd rect
			(at -0.849884 0.499872 90)
			(size 0.254 0.9144)
			(layers "F.Cu" "F.Mask" "F.Paste")
			(net "P1V8_AUX_CS")
		)
		(pad "5" smd circle
			(at -0.94996 0.999998 270)
			(size 0 0)
			(layers "F.Cu" "F.Mask" "F.Paste")
			(net "P1V8_AUX_ENABLE")
		)
		(pad "6" smd circle
			(at -0.249936 1.450086)
			(size 0 0)
			(layers "F.Cu" "F.Mask" "F.Paste")
			(net "P1V8_AUX_FB")
		)
		(pad "7" smd circle
			(at 0.249936 1.450086)
			(size 0 0)
			(layers "F.Cu" "F.Mask" "F.Paste")
			(net "GND")
		)
		(pad "8" smd circle
			(at 0.94996 0.999998 90)
			(size 0 0)
			(layers "F.Cu" "F.Mask" "F.Paste")
			(net "P1V8_AUX_REF")
		)
		(pad "9" smd rect
			(at 0.849884 0.499872 90)
			(size 0.254 0.9144)
			(layers "F.Cu" "F.Mask" "F.Paste")
			(net "PWRGD_P1V8_AUX")
		)
		(pad "10" smd rect
			(at 0.849884 0 90)
			(size 0.254 0.9144)
			(layers "F.Cu" "F.Mask" "F.Paste")
			(net "SW_P1V8_AUX_BT")
		)
		(pad "11" smd rect
			(at 0.849884 -0.499872 90)
			(size 0.254 0.9144)
			(layers "F.Cu" "F.Mask" "F.Paste")
			(net "SW_P1V8_AUX_PH")
		)
		(pad "12" smd circle
			(at 0.94996 -0.999998 90)
			(size 0 0)
			(layers "F.Cu" "F.Mask" "F.Paste")
			(net "P1V8_AUX_MODE")
		)
		(pad "13" smd circle
			(at 0.249936 -1.450086 180)
			(size 0 0)
			(layers "F.Cu" "F.Mask" "F.Paste")
			(net "P1V8_AUX_VCC")
		)
		(pad "14" smd circle
			(at -0.249936 -1.450086 180)
			(size 0 0)
			(layers "F.Cu" "F.Mask" "F.Paste")
			(net "GND")
		)
	)
	(footprint ""
		(layer "F.Cu")
		(at 121.36247 -78.691486 180)
		(property "Reference" "PC6009"
			(at 0 0 180)
			(layer "F.SilkS")
			(hide yes)
			(effects
				(font
					(size 1.27 1.27)
				)
			)
		)
		(property "Value" ""
			(at 0 0 180)
			(layer "F.Fab")
			(effects
				(font
					(size 1.27 1.27)
				)
			)
		)
		(duplicate_pad_numbers_are_jumpers no)
		(fp_line
			(start 0.7874 0.4064)
			(end -0.7874 0.4064)
			(stroke
				(width 0.1524)
				(type default)
			)
			(layer "F.SilkS")
		)
		(fp_line
			(start 0.7874 -0.4064)
			(end 0.7874 0.4064)
			(stroke
				(width 0.1524)
				(type default)
			)
			(layer "F.SilkS")
		)
		(fp_line
			(start -0.7874 0.4064)
			(end -0.7874 -0.4064)
			(stroke
				(width 0.1524)
				(type default)
			)
			(layer "F.SilkS")
		)
		(fp_line
			(start -0.7874 -0.4064)
			(end 0.7874 -0.4064)
			(stroke
				(width 0.1524)
				(type default)
			)
			(layer "F.SilkS")
		)
		(fp_line
			(start 0.67945 0.3048)
			(end 0.120396 0.3048)
			(stroke
				(width 0.1)
				(type default)
			)
			(layer "F.Fab")
		)
		(fp_line
			(start 0.67945 -0.3048)
			(end 0.67945 0.3048)
			(stroke
				(width 0.1)
				(type default)
			)
			(layer "F.Fab")
		)
		(fp_line
			(start 0.12065 -0.2794)
			(end 0.12065 -0.3048)
			(stroke
				(width 0.1)
				(type default)
			)
			(layer "F.Fab")
		)
		(fp_line
			(start 0.12065 -0.3048)
			(end 0.67945 -0.3048)
			(stroke
				(width 0.1)
				(type default)
			)
			(layer "F.Fab")
		)
		(fp_line
			(start 0.120396 0.3048)
			(end 0.120396 0.2794)
			(stroke
				(width 0.1)
				(type default)
			)
			(layer "F.Fab")
		)
		(fp_line
			(start 0.120396 0.2794)
			(end -0.12065 0.2794)
			(stroke
				(width 0.1)
				(type default)
			)
			(layer "F.Fab")
		)
		(fp_line
			(start -0.12065 0.3048)
			(end -0.67945 0.3048)
			(stroke
				(width 0.1)
				(type default)
			)
			(layer "F.Fab")
		)
		(fp_line
			(start -0.12065 0.2794)
			(end -0.12065 0.3048)
			(stroke
				(width 0.1)
				(type default)
			)
			(layer "F.Fab")
		)
		(fp_line
			(start -0.12065 -0.2794)
			(end 0.12065 -0.2794)
			(stroke
				(width 0.1)
				(type default)
			)
			(layer "F.Fab")
		)
		(fp_line
			(start -0.12065 -0.305054)
			(end -0.12065 -0.2794)
			(stroke
				(width 0.1)
				(type default)
			)
			(layer "F.Fab")
		)
		(fp_line
			(start -0.67945 0.3048)
			(end -0.67945 -0.305054)
			(stroke
				(width 0.1)
				(type default)
			)
			(layer "F.Fab")
		)
		(fp_line
			(start -0.67945 -0.305054)
			(end -0.12065 -0.305054)
			(stroke
				(width 0.1)
				(type default)
			)
			(layer "F.Fab")
		)
		(pad "1" smd circle
			(at -0.40005 0 180)
			(size 0 0)
			(layers "F.Cu" "F.Mask" "F.Paste")
			(net "P1V2_AUX_VCC")
		)
		(pad "2" smd circle
			(at 0.40005 0 180)
			(size 0 0)
			(layers "F.Cu" "F.Mask" "F.Paste")
			(net "GND")
		)
	)
	(footprint ""
		(layer "F.Cu")
		(at 106.696764 -173.5201 -90)
		(property "Reference" "PR198"
			(at 0 0 270)
			(layer "F.SilkS")
			(hide yes)
			(effects
				(font
					(size 1.27 1.27)
				)
			)
		)
		(property "Value" ""
			(at 0 0 270)
			(layer "F.Fab")
			(effects
				(font
					(size 1.27 1.27)
				)
			)
		)
		(duplicate_pad_numbers_are_jumpers no)
		(fp_line
			(start -0.7874 0.4064)
			(end -0.7874 -0.4064)
			(stroke
				(width 0.1524)
				(type default)
			)
			(layer "F.SilkS")
		)
		(fp_line
			(start 0.7874 0.4064)
			(end -0.7874 0.4064)
			(stroke
				(width 0.1524)
				(type default)
			)
			(layer "F.SilkS")
		)
		(fp_line
			(start -0.7874 -0.4064)
			(end 0.7874 -0.4064)
			(stroke
				(width 0.1524)
				(type default)
			)
			(layer "F.SilkS")
		)
		(fp_line
			(start 0.7874 -0.4064)
			(end 0.7874 0.4064)
			(stroke
				(width 0.1524)
				(type default)
			)
			(layer "F.SilkS")
		)
		(fp_line
			(start -0.67945 0.3048)
			(end -0.67945 -0.305054)
			(stroke
				(width 0.1)
				(type default)
			)
			(layer "F.Fab")
		)
		(fp_line
			(start -0.12065 0.3048)
			(end -0.67945 0.3048)
			(stroke
				(width 0.1)
				(type default)
			)
			(layer "F.Fab")
		)
		(fp_line
			(start 0.120396 0.3048)
			(end 0.120396 0.2794)
			(stroke
				(width 0.1)
				(type default)
			)
			(layer "F.Fab")
		)
		(fp_line
			(start 0.67945 0.3048)
			(end 0.120396 0.3048)
			(stroke
				(width 0.1)
				(type default)
			)
			(layer "F.Fab")
		)
		(fp_line
			(start -0.12065 0.2794)
			(end -0.12065 0.3048)
			(stroke
				(width 0.1)
				(type default)
			)
			(layer "F.Fab")
		)
		(fp_line
			(start 0.120396 0.2794)
			(end -0.12065 0.2794)
			(stroke
				(width 0.1)
				(type default)
			)
			(layer "F.Fab")
		)
		(fp_line
			(start -0.12065 -0.2794)
			(end 0.12065 -0.2794)
			(stroke
				(width 0.1)
				(type default)
			)
			(layer "F.Fab")
		)
		(fp_line
			(start 0.12065 -0.2794)
			(end 0.12065 -0.3048)
			(stroke
				(width 0.1)
				(type default)
			)
			(layer "F.Fab")
		)
		(fp_line
			(start 0.12065 -0.3048)
			(end 0.67945 -0.3048)
			(stroke
				(width 0.1)
				(type default)
			)
			(layer "F.Fab")
		)
		(fp_line
			(start 0.67945 -0.3048)
			(end 0.67945 0.3048)
			(stroke
				(width 0.1)
				(type default)
			)
			(layer "F.Fab")
		)
		(fp_line
			(start -0.67945 -0.305054)
			(end -0.12065 -0.305054)
			(stroke
				(width 0.1)
				(type default)
			)
			(layer "F.Fab")
		)
		(fp_line
			(start -0.12065 -0.305054)
			(end -0.12065 -0.2794)
			(stroke
				(width 0.1)
				(type default)
			)
			(layer "F.Fab")
		)
		(pad "1" smd circle
			(at -0.40005 0 270)
			(size 0 0)
			(layers "F.Cu" "F.Mask" "F.Paste")
			(net "SW_PVDDCR_CPU0_P1_BOOT4")
		)
		(pad "2" smd circle
			(at 0.40005 0 270)
			(size 0 0)
			(layers "F.Cu" "F.Mask" "F.Paste")
			(net "SW_PVDDCR_CPU0_P1_BOOT4_RC")
		)
	)
	(footprint ""
		(layer "F.Cu")
		(at 34.379662 -429.790098 90)
		(property "Reference" "R3267"
			(at 0 0 90)
			(layer "F.SilkS")
			(hide yes)
			(effects
				(font
					(size 1.27 1.27)
				)
			)
		)
		(property "Value" ""
			(at 0 0 90)
			(layer "F.Fab")
			(effects
				(font
					(size 1.27 1.27)
				)
			)
		)
		(duplicate_pad_numbers_are_jumpers no)
		(fp_line
			(start 0.7874 -0.4064)
			(end 0.7874 0.4064)
			(stroke
				(width 0.1524)
				(type default)
			)
			(layer "F.SilkS")
		)
		(fp_line
			(start -0.7874 -0.4064)
			(end 0.7874 -0.4064)
			(stroke
				(width 0.1524)
				(type default)
			)
			(layer "F.SilkS")
		)
		(fp_line
			(start 0.7874 0.4064)
			(end -0.7874 0.4064)
			(stroke
				(width 0.1524)
				(type default)
			)
			(layer "F.SilkS")
		)
		(fp_line
			(start -0.7874 0.4064)
			(end -0.7874 -0.4064)
			(stroke
				(width 0.1524)
				(type default)
			)
			(layer "F.SilkS")
		)
		(fp_line
			(start -0.12065 -0.305054)
			(end -0.12065 -0.2794)
			(stroke
				(width 0.1)
				(type default)
			)
			(layer "F.Fab")
		)
		(fp_line
			(start -0.67945 -0.305054)
			(end -0.12065 -0.305054)
			(stroke
				(width 0.1)
				(type default)
			)
			(layer "F.Fab")
		)
		(fp_line
			(start 0.67945 -0.3048)
			(end 0.67945 0.3048)
			(stroke
				(width 0.1)
				(type default)
			)
			(layer "F.Fab")
		)
		(fp_line
			(start 0.12065 -0.3048)
			(end 0.67945 -0.3048)
			(stroke
				(width 0.1)
				(type default)
			)
			(layer "F.Fab")
		)
		(fp_line
			(start 0.12065 -0.2794)
			(end 0.12065 -0.3048)
			(stroke
				(width 0.1)
				(type default)
			)
			(layer "F.Fab")
		)
		(fp_line
			(start -0.12065 -0.2794)
			(end 0.12065 -0.2794)
			(stroke
				(width 0.1)
				(type default)
			)
			(layer "F.Fab")
		)
		(fp_line
			(start 0.120396 0.2794)
			(end -0.12065 0.2794)
			(stroke
				(width 0.1)
				(type default)
			)
			(layer "F.Fab")
		)
		(fp_line
			(start -0.12065 0.2794)
			(end -0.12065 0.3048)
			(stroke
				(width 0.1)
				(type default)
			)
			(layer "F.Fab")
		)
		(fp_line
			(start 0.67945 0.3048)
			(end 0.120396 0.3048)
			(stroke
				(width 0.1)
				(type default)
			)
			(layer "F.Fab")
		)
		(fp_line
			(start 0.120396 0.3048)
			(end 0.120396 0.2794)
			(stroke
				(width 0.1)
				(type default)
			)
			(layer "F.Fab")
		)
		(fp_line
			(start -0.12065 0.3048)
			(end -0.67945 0.3048)
			(stroke
				(width 0.1)
				(type default)
			)
			(layer "F.Fab")
		)
		(fp_line
			(start -0.67945 0.3048)
			(end -0.67945 -0.305054)
			(stroke
				(width 0.1)
				(type default)
			)
			(layer "F.Fab")
		)
		(pad "1" smd circle
			(at -0.40005 0 90)
			(size 0 0)
			(layers "F.Cu" "F.Mask" "F.Paste")
			(net "FM_P2E_FGB")
		)
		(pad "2" smd circle
			(at 0.40005 0 90)
			(size 0 0)
			(layers "F.Cu" "F.Mask" "F.Paste")
			(net "GND")
		)
	)
	(footprint ""
		(layer "F.Cu")
		(at 446.258442 -53.188108 90)
		(property "Reference" "PC2261"
			(at 0 0 90)
			(layer "F.SilkS")
			(hide yes)
			(effects
				(font
					(size 1.27 1.27)
				)
			)
		)
		(property "Value" ""
			(at 0 0 90)
			(layer "F.Fab")
			(effects
				(font
					(size 1.27 1.27)
				)
			)
		)
		(duplicate_pad_numbers_are_jumpers no)
		(fp_line
			(start 1.524 -0.762)
			(end 1.524 0.762)
			(stroke
				(width 0.1524)
				(type default)
			)
			(layer "F.SilkS")
		)
		(fp_line
			(start -1.524 -0.762)
			(end 1.524 -0.762)
			(stroke
				(width 0.1524)
				(type default)
			)
			(layer "F.SilkS")
		)
		(fp_line
			(start 1.524 0.762)
			(end -1.524 0.762)
			(stroke
				(width 0.1524)
				(type default)
			)
			(layer "F.SilkS")
		)
		(fp_line
			(start -1.524 0.762)
			(end -1.524 -0.762)
			(stroke
				(width 0.1524)
				(type default)
			)
			(layer "F.SilkS")
		)
		(fp_line
			(start 1.1049 -0.724916)
			(end -1.1049 -0.724916)
			(stroke
				(width 0.1)
				(type default)
			)
			(layer "F.Fab")
		)
		(fp_line
			(start -1.1049 -0.724916)
			(end -1.1049 0.724916)
			(stroke
				(width 0.1)
				(type default)
			)
			(layer "F.Fab")
		)
		(fp_line
			(start 1.1049 0.724916)
			(end 1.1049 -0.724916)
			(stroke
				(width 0.1)
				(type default)
			)
			(layer "F.Fab")
		)
		(fp_line
			(start -1.1049 0.724916)
			(end 1.1049 0.724916)
			(stroke
				(width 0.1)
				(type default)
			)
			(layer "F.Fab")
		)
		(pad "1" smd rect
			(at -0.889 0 270)
			(size 1.016 1.27)
			(layers "F.Cu" "F.Mask" "F.Paste")
			(net "SW_P3V3_AUX_FLT")
		)
		(pad "2" smd rect
			(at 0.889 0 270)
			(size 1.016 1.27)
			(layers "F.Cu" "F.Mask" "F.Paste")
			(net "GND")
		)
	)
	(footprint ""
		(layer "F.Cu")
		(at 20.480782 -410.564584 180)
		(property "Reference" "PR6806"
			(at 0 0 180)
			(layer "F.SilkS")
			(hide yes)
			(effects
				(font
					(size 1.27 1.27)
				)
			)
		)
		(property "Value" ""
			(at 0 0 180)
			(layer "F.Fab")
			(effects
				(font
					(size 1.27 1.27)
				)
			)
		)
		(duplicate_pad_numbers_are_jumpers no)
		(fp_line
			(start 0.7874 0.4064)
			(end -0.7874 0.4064)
			(stroke
				(width 0.1524)
				(type default)
			)
			(layer "F.SilkS")
		)
		(fp_line
			(start 0.7874 -0.4064)
			(end 0.7874 0.4064)
			(stroke
				(width 0.1524)
				(type default)
			)
			(layer "F.SilkS")
		)
		(fp_line
			(start -0.7874 0.4064)
			(end -0.7874 -0.4064)
			(stroke
				(width 0.1524)
				(type default)
			)
			(layer "F.SilkS")
		)
		(fp_line
			(start -0.7874 -0.4064)
			(end 0.7874 -0.4064)
			(stroke
				(width 0.1524)
				(type default)
			)
			(layer "F.SilkS")
		)
		(fp_line
			(start 0.67945 0.3048)
			(end 0.120396 0.3048)
			(stroke
				(width 0.1)
				(type default)
			)
			(layer "F.Fab")
		)
		(fp_line
			(start 0.67945 -0.3048)
			(end 0.67945 0.3048)
			(stroke
				(width 0.1)
				(type default)
			)
			(layer "F.Fab")
		)
		(fp_line
			(start 0.12065 -0.2794)
			(end 0.12065 -0.3048)
			(stroke
				(width 0.1)
				(type default)
			)
			(layer "F.Fab")
		)
		(fp_line
			(start 0.12065 -0.3048)
			(end 0.67945 -0.3048)
			(stroke
				(width 0.1)
				(type default)
			)
			(layer "F.Fab")
		)
		(fp_line
			(start 0.120396 0.3048)
			(end 0.120396 0.2794)
			(stroke
				(width 0.1)
				(type default)
			)
			(layer "F.Fab")
		)
		(fp_line
			(start 0.120396 0.2794)
			(end -0.12065 0.2794)
			(stroke
				(width 0.1)
				(type default)
			)
			(layer "F.Fab")
		)
		(fp_line
			(start -0.12065 0.3048)
			(end -0.67945 0.3048)
			(stroke
				(width 0.1)
				(type default)
			)
			(layer "F.Fab")
		)
		(fp_line
			(start -0.12065 0.2794)
			(end -0.12065 0.3048)
			(stroke
				(width 0.1)
				(type default)
			)
			(layer "F.Fab")
		)
		(fp_line
			(start -0.12065 -0.2794)
			(end 0.12065 -0.2794)
			(stroke
				(width 0.1)
				(type default)
			)
			(layer "F.Fab")
		)
		(fp_line
			(start -0.12065 -0.305054)
			(end -0.12065 -0.2794)
			(stroke
				(width 0.1)
				(type default)
			)
			(layer "F.Fab")
		)
		(fp_line
			(start -0.67945 0.3048)
			(end -0.67945 -0.305054)
			(stroke
				(width 0.1)
				(type default)
			)
			(layer "F.Fab")
		)
		(fp_line
			(start -0.67945 -0.305054)
			(end -0.12065 -0.305054)
			(stroke
				(width 0.1)
				(type default)
			)
			(layer "F.Fab")
		)
		(pad "1" smd circle
			(at -0.40005 0 180)
			(size 0 0)
			(layers "F.Cu" "F.Mask" "F.Paste")
			(net "P3V3_AUX")
		)
		(pad "2" smd circle
			(at 0.40005 0 180)
			(size 0 0)
			(layers "F.Cu" "F.Mask" "F.Paste")
			(net "P0V9_RETIMER_CPU1_SVID_CLK")
		)
	)
)
